(kicad_pcb
	(version 20260206)
	(generator "pcbnew")
	(generator_version "10.0")
	(general
		(thickness 1.6)
		(legacy_teardrops no)
	)
	(paper "A4")
	(title_block
		(title "v1-chassis-manager — T6M_CM_d_v01_1031_1645.brd")
		(comment 1 "Open CloudServer (Microsoft) / footprints 653-661 of 2512")
	)
	(layers
		(0 "F.Cu" signal "TOP")
		(4 "In1.Cu" signal "GND1")
		(6 "In2.Cu" signal "IN1")
		(8 "In3.Cu" signal "VCC1")
		(10 "In4.Cu" signal "VCC2")
		(12 "In5.Cu" signal "GND2")
		(14 "In6.Cu" signal "IN2")
		(16 "In7.Cu" signal "IN3")
		(18 "In8.Cu" signal "GND3")
		(2 "B.Cu" signal "BOTTOM")
		(9 "F.Adhes" user "F.Adhesive")
		(11 "B.Adhes" user "B.Adhesive")
		(13 "F.Paste" user "Package Geometry/Pastemask Top")
		(15 "B.Paste" user "Package Geometry/Pastemask Bottom")
		(5 "F.SilkS" user "Ref Des/Silkscreen Top")
		(7 "B.SilkS" user "Ref Des/Silkscreen Bottom")
		(1 "F.Mask" user "Board Geometry/Soldermask Top")
		(3 "B.Mask" user "Board Geometry/Soldermask Bottom")
		(17 "Dwgs.User" user "User.Drawings")
		(19 "Cmts.User" user "User.Comments")
		(21 "Eco1.User" user "User.Eco1")
		(23 "Eco2.User" user "User.Eco2")
		(25 "Edge.Cuts" user "Board Geometry/Outline")
		(27 "Margin" user)
		(31 "F.CrtYd" user "Package Geometry/Place Bound Top")
		(29 "B.CrtYd" user "Package Geometry/Place Bound Bottom")
		(35 "F.Fab" user "Ref Des/Assembly Top")
		(33 "B.Fab" user "Ref Des/Assembly Bottom")
	)
	(footprint ""
		(layer "F.Cu")
		(at 5.076698 -97.303336 90)
		(property "Reference" "D28"
			(at 3.628644 0.295148 90)
			(unlocked yes)
			(layer "F.SilkS")
			(effects
				(font
					(size 0.7874 0.5842)
					(thickness 0.1524)
				)
				(justify left)
			)
		)
		(property "Value" ""
			(at 0 0 90)
			(layer "F.Fab")
			(effects
				(font
					(size 1.27 1.27)
				)
			)
		)
		(duplicate_pad_numbers_are_jumpers no)
		(fp_line
			(start 3.429 -1.397)
			(end -3.175 -1.397)
			(stroke
				(width 0.1524)
				(type default)
			)
			(layer "F.SilkS")
		)
		(fp_line
			(start 3.302 -1.397)
			(end 3.302 1.397)
			(stroke
				(width 0.1524)
				(type default)
			)
			(layer "F.SilkS")
		)
		(fp_line
			(start -3.175 -1.397)
			(end -3.175 1.397)
			(stroke
				(width 0.1524)
				(type default)
			)
			(layer "F.SilkS")
		)
		(fp_line
			(start 0.299974 -0.500126)
			(end 0.299974 0.500126)
			(stroke
				(width 0.1524)
				(type default)
			)
			(layer "F.SilkS")
		)
		(fp_line
			(start -0.299974 -0.500126)
			(end -0.299974 0.500126)
			(stroke
				(width 0.1524)
				(type default)
			)
			(layer "F.SilkS")
		)
		(fp_line
			(start 0.199898 0)
			(end -0.299974 -0.500126)
			(stroke
				(width 0.1524)
				(type default)
			)
			(layer "F.SilkS")
		)
		(fp_line
			(start -0.299974 0.500126)
			(end 0.199898 0)
			(stroke
				(width 0.1524)
				(type default)
			)
			(layer "F.SilkS")
		)
		(fp_line
			(start 3.429 1.397)
			(end 3.429 -1.397)
			(stroke
				(width 0.1524)
				(type default)
			)
			(layer "F.SilkS")
		)
		(fp_line
			(start 3.302 1.397)
			(end 3.299968 1.400048)
			(stroke
				(width 0.1524)
				(type default)
			)
			(layer "F.SilkS")
		)
		(fp_line
			(start 3.175 1.397)
			(end 3.175 -1.397)
			(stroke
				(width 0.1524)
				(type default)
			)
			(layer "F.SilkS")
		)
		(fp_line
			(start -3.175 1.397)
			(end 3.429 1.397)
			(stroke
				(width 0.1524)
				(type default)
			)
			(layer "F.SilkS")
		)
		(fp_poly
			(pts
				(xy -2.6416 1.397) (xy -2.6416 1.016) (xy -3.0226 1.016) (xy -3.0226 -1.016) (xy -2.667 -1.016)
				(xy -2.667 -1.397) (xy 2.667 -1.397) (xy 2.667 -1.016) (xy 3.0226 -1.016) (xy 3.0226 1.016) (xy 2.667 1.016)
				(xy 2.667 1.397)
			)
			(stroke
				(width 0)
				(type default)
			)
			(fill no)
			(layer "F.CrtYd")
		)
		(pad "1" smd rect
			(at -2.249932 0 270)
			(size 1.524 2.032)
			(layers "F.Cu" "F.Mask" "F.Paste")
			(net "P12V_DBG")
		)
		(pad "2" smd rect
			(at 2.249932 0 90)
			(size 1.524 2.032)
			(layers "F.Cu" "F.Mask" "F.Paste")
			(net "P12V_PDB")
		)
	)
	(footprint ""
		(layer "F.Cu")
		(at 167.626538 -12.491974 90)
		(property "Reference" "R1197"
			(at -0.857504 -1.986788 90)
			(unlocked yes)
			(layer "F.SilkS")
			(effects
				(font
					(size 0.7874 0.5842)
					(thickness 0.1524)
				)
				(justify left)
			)
		)
		(property "Value" ""
			(at 0 0 90)
			(layer "F.Fab")
			(effects
				(font
					(size 1.27 1.27)
				)
			)
		)
		(duplicate_pad_numbers_are_jumpers no)
		(fp_line
			(start 0.7874 -0.4064)
			(end 0.7874 0.4064)
			(stroke
				(width 0.1524)
				(type default)
			)
			(layer "F.SilkS")
		)
		(fp_line
			(start -0.7874 -0.4064)
			(end 0.7874 -0.4064)
			(stroke
				(width 0.1524)
				(type default)
			)
			(layer "F.SilkS")
		)
		(fp_line
			(start 0.7874 0.4064)
			(end -0.7874 0.4064)
			(stroke
				(width 0.1524)
				(type default)
			)
			(layer "F.SilkS")
		)
		(fp_line
			(start -0.7874 0.4064)
			(end -0.7874 -0.4064)
			(stroke
				(width 0.1524)
				(type default)
			)
			(layer "F.SilkS")
		)
		(fp_poly
			(pts
				(xy -0.508 0.2794) (xy -0.508 0.2286) (xy -0.635 0.2286) (xy -0.635 -0.254) (xy -0.5334 -0.254)
				(xy -0.5334 -0.2794) (xy 0.5334 -0.2794) (xy 0.5334 -0.254) (xy 0.635 -0.254) (xy 0.635 0.254) (xy 0.5334 0.254)
				(xy 0.5334 0.2794)
			)
			(stroke
				(width 0)
				(type default)
			)
			(fill no)
			(layer "F.CrtYd")
		)
		(pad "1" smd rect
			(at 0.40005 0 90)
			(size 0.4572 0.508)
			(layers "F.Cu" "F.Mask" "F.Paste")
			(net "SIO_JTAG_CPLD3_TMS")
		)
		(pad "2" smd rect
			(at -0.40005 0 90)
			(size 0.4572 0.508)
			(layers "F.Cu" "F.Mask" "F.Paste")
			(net "JTAG_CPLD3_TMS")
		)
	)
	(footprint ""
		(layer "F.Cu")
		(at 115.478814 -132.313934 -90)
		(property "Reference" "PC98"
			(at -0.481838 -4.604512 90)
			(unlocked yes)
			(layer "F.SilkS")
			(effects
				(font
					(size 0.7874 0.5842)
					(thickness 0.1524)
				)
			)
		)
		(property "Value" ""
			(at 0 0 270)
			(layer "F.Fab")
			(effects
				(font
					(size 1.27 1.27)
				)
			)
		)
		(duplicate_pad_numbers_are_jumpers no)
		(fp_line
			(start -1.2954 0.5842)
			(end -1.2954 -0.5842)
			(stroke
				(width 0.1524)
				(type default)
			)
			(layer "F.SilkS")
		)
		(fp_line
			(start 1.2954 0.5842)
			(end -1.2954 0.5842)
			(stroke
				(width 0.1524)
				(type default)
			)
			(layer "F.SilkS")
		)
		(fp_line
			(start -1.2954 -0.5842)
			(end 1.2954 -0.5842)
			(stroke
				(width 0.1524)
				(type default)
			)
			(layer "F.SilkS")
		)
		(fp_line
			(start 0 -0.5842)
			(end 0 0.5842)
			(stroke
				(width 0.1524)
				(type default)
			)
			(layer "F.SilkS")
		)
		(fp_line
			(start 1.2954 -0.5842)
			(end 1.2954 0.5842)
			(stroke
				(width 0.1524)
				(type default)
			)
			(layer "F.SilkS")
		)
		(fp_poly
			(pts
				(xy 0.8636 -0.4572) (xy 0.8636 -0.3556) (xy 1.143 -0.3556) (xy 1.143 0.3556) (xy 0.8636 0.3556)
				(xy 0.8636 0.4572) (xy -0.8636 0.4572) (xy -0.8636 0.3556) (xy -1.143 0.3556) (xy -1.143 -0.3556)
				(xy -0.8636 -0.3556) (xy -0.8636 -0.4572)
			)
			(stroke
				(width 0)
				(type default)
			)
			(fill no)
			(layer "F.CrtYd")
		)
		(fp_line
			(start -0.884936 0.504952)
			(end -0.884936 -0.504952)
			(stroke
				(width 0.1)
				(type default)
			)
			(layer "F.Fab")
		)
		(fp_line
			(start 0.884936 0.504952)
			(end -0.884936 0.504952)
			(stroke
				(width 0.1)
				(type default)
			)
			(layer "F.Fab")
		)
		(fp_line
			(start -0.884936 -0.504952)
			(end 0.884936 -0.504952)
			(stroke
				(width 0.1)
				(type default)
			)
			(layer "F.Fab")
		)
		(fp_line
			(start 0.884936 -0.504952)
			(end 0.884936 0.504952)
			(stroke
				(width 0.1)
				(type default)
			)
			(layer "F.Fab")
		)
		(pad "1" smd rect
			(at 0.7366 0)
			(size 0.7112 0.8128)
			(layers "F.Cu" "F.Mask" "F.Paste")
			(net "VR_PVCCP_NODE1_ISEN1P_CC")
		)
		(pad "2" smd rect
			(at -0.7366 0)
			(size 0.7112 0.8128)
			(layers "F.Cu" "F.Mask" "F.Paste")
			(net "ISENSE_PVCCP_NODE1_ISEN1N")
		)
	)
	(footprint ""
		(layer "F.Cu")
		(at 138.0236 -160.243774 -90)
		(property "Reference" "R1055"
			(at 109.132624 63.662814 90)
			(unlocked yes)
			(layer "F.SilkS")
			(effects
				(font
					(size 0.7874 0.5842)
					(thickness 0.1524)
				)
				(justify left)
			)
		)
		(property "Value" ""
			(at 0 0 270)
			(layer "F.Fab")
			(effects
				(font
					(size 1.27 1.27)
				)
			)
		)
		(duplicate_pad_numbers_are_jumpers no)
		(fp_line
			(start -0.7874 0.4064)
			(end -0.7874 -0.4064)
			(stroke
				(width 0.1524)
				(type default)
			)
			(layer "F.SilkS")
		)
		(fp_line
			(start 0.7874 0.4064)
			(end -0.7874 0.4064)
			(stroke
				(width 0.1524)
				(type default)
			)
			(layer "F.SilkS")
		)
		(fp_line
			(start -0.7874 -0.4064)
			(end 0.7874 -0.4064)
			(stroke
				(width 0.1524)
				(type default)
			)
			(layer "F.SilkS")
		)
		(fp_line
			(start 0.7874 -0.4064)
			(end 0.7874 0.4064)
			(stroke
				(width 0.1524)
				(type default)
			)
			(layer "F.SilkS")
		)
		(fp_poly
			(pts
				(xy -0.508 0.2794) (xy -0.508 0.2286) (xy -0.635 0.2286) (xy -0.635 -0.254) (xy -0.5334 -0.254)
				(xy -0.5334 -0.2794) (xy 0.5334 -0.2794) (xy 0.5334 -0.254) (xy 0.635 -0.254) (xy 0.635 0.254) (xy 0.5334 0.254)
				(xy 0.5334 0.2794)
			)
			(stroke
				(width 0)
				(type default)
			)
			(fill no)
			(layer "F.CrtYd")
		)
		(pad "1" smd rect
			(at 0.40005 0 270)
			(size 0.4572 0.508)
			(layers "F.Cu" "F.Mask" "F.Paste")
			(net "N31521711")
		)
		(pad "2" smd rect
			(at -0.40005 0 270)
			(size 0.4572 0.508)
			(layers "F.Cu" "F.Mask" "F.Paste")
			(net "CLK_33K_CPLD23")
		)
	)
	(footprint ""
		(layer "F.Cu")
		(at 134.486396 -130.487166 90)
		(property "Reference" "C190"
			(at -1.572768 2.173478 90)
			(unlocked yes)
			(layer "F.SilkS")
			(effects
				(font
					(size 0.7874 0.5842)
					(thickness 0.1524)
				)
				(justify left)
			)
		)
		(property "Value" ""
			(at 0 0 90)
			(layer "F.Fab")
			(effects
				(font
					(size 1.27 1.27)
				)
			)
		)
		(duplicate_pad_numbers_are_jumpers no)
		(fp_line
			(start 0.7874 -0.4064)
			(end 0.7874 0.4064)
			(stroke
				(width 0.1524)
				(type default)
			)
			(layer "F.SilkS")
		)
		(fp_line
			(start -0.7874 -0.4064)
			(end 0.7874 -0.4064)
			(stroke
				(width 0.1524)
				(type default)
			)
			(layer "F.SilkS")
		)
		(fp_line
			(start 0 0.381)
			(end 0 -0.381)
			(stroke
				(width 0.1524)
				(type default)
			)
			(layer "F.SilkS")
		)
		(fp_line
			(start 0.7874 0.4064)
			(end -0.7874 0.4064)
			(stroke
				(width 0.1524)
				(type default)
			)
			(layer "F.SilkS")
		)
		(fp_line
			(start -0.7874 0.4064)
			(end -0.7874 -0.4064)
			(stroke
				(width 0.1524)
				(type default)
			)
			(layer "F.SilkS")
		)
		(fp_poly
			(pts
				(xy -0.5334 0.254) (xy -0.635 0.254) (xy -0.635 0.2286) (xy -0.635 -0.254) (xy -0.5334 -0.254) (xy -0.5334 -0.2794)
				(xy 0.5334 -0.2794) (xy 0.5334 -0.254) (xy 0.635 -0.254) (xy 0.635 0.254) (xy 0.5334 0.254) (xy 0.5334 0.2794)
				(xy -0.508 0.2794) (xy -0.5334 0.2794)
			)
			(stroke
				(width 0)
				(type default)
			)
			(fill no)
			(layer "F.CrtYd")
		)
		(pad "1" smd rect
			(at 0.40005 0 90)
			(size 0.4572 0.508)
			(layers "F.Cu" "F.Mask" "F.Paste")
			(net "P2E_CPU_USB_NODE1_TX_C_DN")
		)
		(pad "2" smd rect
			(at -0.40005 0 90)
			(size 0.4572 0.508)
			(layers "F.Cu" "F.Mask" "F.Paste")
			(net "P2E_CPU_USB_NODE1_TX_DN")
		)
	)
	(footprint ""
		(layer "F.Cu")
		(at 126.845822 -113.104676)
		(property "Reference" "R7"
			(at -0.67183 -2.176526 0)
			(unlocked yes)
			(layer "F.SilkS")
			(effects
				(font
					(size 0.7874 0.5842)
					(thickness 0.1524)
				)
				(justify left)
			)
		)
		(property "Value" ""
			(at 0 0 0)
			(layer "F.Fab")
			(effects
				(font
					(size 1.27 1.27)
				)
			)
		)
		(duplicate_pad_numbers_are_jumpers no)
		(fp_line
			(start -0.7874 -0.4064)
			(end 0.7874 -0.4064)
			(stroke
				(width 0.1524)
				(type default)
			)
			(layer "F.SilkS")
		)
		(fp_line
			(start -0.7874 0.4064)
			(end -0.7874 -0.4064)
			(stroke
				(width 0.1524)
				(type default)
			)
			(layer "F.SilkS")
		)
		(fp_line
			(start 0.7874 -0.4064)
			(end 0.7874 0.4064)
			(stroke
				(width 0.1524)
				(type default)
			)
			(layer "F.SilkS")
		)
		(fp_line
			(start 0.7874 0.4064)
			(end -0.7874 0.4064)
			(stroke
				(width 0.1524)
				(type default)
			)
			(layer "F.SilkS")
		)
		(fp_poly
			(pts
				(xy -0.508 0.2794) (xy -0.508 0.2286) (xy -0.635 0.2286) (xy -0.635 -0.254) (xy -0.5334 -0.254)
				(xy -0.5334 -0.2794) (xy 0.5334 -0.2794) (xy 0.5334 -0.254) (xy 0.635 -0.254) (xy 0.635 0.254) (xy 0.5334 0.254)
				(xy 0.5334 0.2794)
			)
			(stroke
				(width 0)
				(type default)
			)
			(fill no)
			(layer "F.CrtYd")
		)
		(pad "1" smd rect
			(at 0.40005 0)
			(size 0.4572 0.508)
			(layers "F.Cu" "F.Mask" "F.Paste")
			(net "FM_CPLD_CLK_R_PG_NODE1_R")
		)
		(pad "2" smd rect
			(at -0.40005 0)
			(size 0.4572 0.508)
			(layers "F.Cu" "F.Mask" "F.Paste")
			(net "FM_CPLD_NODE1_CLK_PG")
		)
	)
	(footprint ""
		(layer "F.Cu")
		(at 66.750692 -107.316016 90)
		(property "Reference" "C848"
			(at -1.118616 7.779258 90)
			(unlocked yes)
			(layer "F.SilkS")
			(effects
				(font
					(size 0.7874 0.5842)
					(thickness 0.1524)
				)
				(justify left)
			)
		)
		(property "Value" ""
			(at 0 0 90)
			(layer "F.Fab")
			(effects
				(font
					(size 1.27 1.27)
				)
			)
		)
		(duplicate_pad_numbers_are_jumpers no)
		(fp_line
			(start 0.7874 -0.4064)
			(end 0.7874 0.4064)
			(stroke
				(width 0.1524)
				(type default)
			)
			(layer "F.SilkS")
		)
		(fp_line
			(start -0.7874 -0.4064)
			(end 0.7874 -0.4064)
			(stroke
				(width 0.1524)
				(type default)
			)
			(layer "F.SilkS")
		)
		(fp_line
			(start 0 0.381)
			(end 0 -0.381)
			(stroke
				(width 0.1524)
				(type default)
			)
			(layer "F.SilkS")
		)
		(fp_line
			(start 0.7874 0.4064)
			(end -0.7874 0.4064)
			(stroke
				(width 0.1524)
				(type default)
			)
			(layer "F.SilkS")
		)
		(fp_line
			(start -0.7874 0.4064)
			(end -0.7874 -0.4064)
			(stroke
				(width 0.1524)
				(type default)
			)
			(layer "F.SilkS")
		)
		(fp_poly
			(pts
				(xy -0.5334 0.254) (xy -0.635 0.254) (xy -0.635 0.2286) (xy -0.635 -0.254) (xy -0.5334 -0.254) (xy -0.5334 -0.2794)
				(xy 0.5334 -0.2794) (xy 0.5334 -0.254) (xy 0.635 -0.254) (xy 0.635 0.254) (xy 0.5334 0.254) (xy 0.5334 0.2794)
				(xy -0.508 0.2794) (xy -0.5334 0.2794)
			)
			(stroke
				(width 0)
				(type default)
			)
			(fill no)
			(layer "F.CrtYd")
		)
		(pad "1" smd rect
			(at 0.40005 0 90)
			(size 0.4572 0.508)
			(layers "F.Cu" "F.Mask" "F.Paste")
			(net "FM_CPLD_NODE1_P1V8_EN")
		)
		(pad "2" smd rect
			(at -0.40005 0 90)
			(size 0.4572 0.508)
			(layers "F.Cu" "F.Mask" "F.Paste")
			(net "GND")
		)
	)
	(footprint ""
		(layer "F.Cu")
		(at 82.587592 -154.80792 180)
		(property "Reference" "PC8"
			(at -1.15062 -0.239776 0)
			(unlocked yes)
			(layer "F.SilkS")
			(effects
				(font
					(size 0.7874 0.5842)
					(thickness 0.1524)
				)
				(justify left)
			)
		)
		(property "Value" ""
			(at 0 0 180)
			(layer "F.Fab")
			(effects
				(font
					(size 1.27 1.27)
				)
			)
		)
		(duplicate_pad_numbers_are_jumpers no)
		(fp_line
			(start 0.7874 0.4064)
			(end -0.7874 0.4064)
			(stroke
				(width 0.1524)
				(type default)
			)
			(layer "F.SilkS")
		)
		(fp_line
			(start 0.7874 -0.4064)
			(end 0.7874 0.4064)
			(stroke
				(width 0.1524)
				(type default)
			)
			(layer "F.SilkS")
		)
		(fp_line
			(start 0 0.381)
			(end 0 -0.381)
			(stroke
				(width 0.1524)
				(type default)
			)
			(layer "F.SilkS")
		)
		(fp_line
			(start -0.7874 0.4064)
			(end -0.7874 -0.4064)
			(stroke
				(width 0.1524)
				(type default)
			)
			(layer "F.SilkS")
		)
		(fp_line
			(start -0.7874 -0.4064)
			(end 0.7874 -0.4064)
			(stroke
				(width 0.1524)
				(type default)
			)
			(layer "F.SilkS")
		)
		(fp_poly
			(pts
				(xy -0.5334 0.254) (xy -0.635 0.254) (xy -0.635 0.2286) (xy -0.635 -0.254) (xy -0.5334 -0.254) (xy -0.5334 -0.2794)
				(xy 0.5334 -0.2794) (xy 0.5334 -0.254) (xy 0.635 -0.254) (xy 0.635 0.254) (xy 0.5334 0.254) (xy 0.5334 0.2794)
				(xy -0.508 0.2794) (xy -0.5334 0.2794)
			)
			(stroke
				(width 0)
				(type default)
			)
			(fill no)
			(layer "F.CrtYd")
		)
		(pad "1" smd rect
			(at 0.40005 0 180)
			(size 0.4572 0.508)
			(layers "F.Cu" "F.Mask" "F.Paste")
			(net "P5V_STB_NODE1_VREG5")
		)
		(pad "2" smd rect
			(at -0.40005 0 180)
			(size 0.4572 0.508)
			(layers "F.Cu" "F.Mask" "F.Paste")
			(net "GND")
		)
	)
	(footprint ""
		(layer "F.Cu")
		(at 155.356814 -66.498216)
		(property "Reference" "C489"
			(at -0.53086 2.179574 0)
			(unlocked yes)
			(layer "F.SilkS")
			(effects
				(font
					(size 0.7874 0.5842)
					(thickness 0.1524)
				)
				(justify left)
			)
		)
		(property "Value" ""
			(at 0 0 0)
			(layer "F.Fab")
			(effects
				(font
					(size 1.27 1.27)
				)
			)
		)
		(duplicate_pad_numbers_are_jumpers no)
		(fp_line
			(start -0.7874 -0.4064)
			(end 0.7874 -0.4064)
			(stroke
				(width 0.1524)
				(type default)
			)
			(layer "F.SilkS")
		)
		(fp_line
			(start -0.7874 0.4064)
			(end -0.7874 -0.4064)
			(stroke
				(width 0.1524)
				(type default)
			)
			(layer "F.SilkS")
		)
		(fp_line
			(start 0 0.381)
			(end 0 -0.381)
			(stroke
				(width 0.1524)
				(type default)
			)
			(layer "F.SilkS")
		)
		(fp_line
			(start 0.7874 -0.4064)
			(end 0.7874 0.4064)
			(stroke
				(width 0.1524)
				(type default)
			)
			(layer "F.SilkS")
		)
		(fp_line
			(start 0.7874 0.4064)
			(end -0.7874 0.4064)
			(stroke
				(width 0.1524)
				(type default)
			)
			(layer "F.SilkS")
		)
		(fp_poly
			(pts
				(xy -0.5334 0.254) (xy -0.635 0.254) (xy -0.635 0.2286) (xy -0.635 -0.254) (xy -0.5334 -0.254) (xy -0.5334 -0.2794)
				(xy 0.5334 -0.2794) (xy 0.5334 -0.254) (xy 0.635 -0.254) (xy 0.635 0.254) (xy 0.5334 0.254) (xy 0.5334 0.2794)
				(xy -0.508 0.2794) (xy -0.5334 0.2794)
			)
			(stroke
				(width 0)
				(type default)
			)
			(fill no)
			(layer "F.CrtYd")
		)
		(pad "1" smd rect
			(at 0.40005 0)
			(size 0.4572 0.508)
			(layers "F.Cu" "F.Mask" "F.Paste")
			(net "SATA_TX0_C_DP")
		)
		(pad "2" smd rect
			(at -0.40005 0)
			(size 0.4572 0.508)
			(layers "F.Cu" "F.Mask" "F.Paste")
			(net "SATA_A_NODE1_TX_P0")
		)
	)
)
